(kicad_pcb
	(version 20260206)
	(generator "pcbnew")
	(generator_version "10.0")
	(general
		(thickness 1.6)
		(legacy_teardrops no)
	)
	(paper "A4")
	(title_block
		(title "01162023_DA0F0TEBIF0_F0T_Expander_BD_F_brd_V02_OCP.brd")
		(comment 1 "Grand Teton / footprints 9650-9654 of 9728")
	)
	(layers
		(0 "F.Cu" signal "TOP")
		(4 "In1.Cu" signal "GND")
		(6 "In2.Cu" signal "VCC")
		(8 "In3.Cu" signal "VCC1")
		(10 "In4.Cu" signal "GND1")
		(12 "In5.Cu" signal "IN1")
		(14 "In6.Cu" signal "GND2")
		(16 "In7.Cu" signal "IN2")
		(18 "In8.Cu" signal "GND3")
		(20 "In9.Cu" signal "IN3")
		(22 "In10.Cu" signal "GND4")
		(24 "In11.Cu" signal "IN4")
		(26 "In12.Cu" signal "GND5")
		(28 "In13.Cu" signal "IN5")
		(30 "In14.Cu" signal "GND6")
		(32 "In15.Cu" signal "IN6")
		(34 "In16.Cu" signal "GND7")
		(2 "B.Cu" signal "BOTTOM")
		(9 "F.Adhes" user "F.Adhesive")
		(11 "B.Adhes" user "B.Adhesive")
		(13 "F.Paste" user "Package Geometry/Pastemask Top")
		(15 "B.Paste" user "Package Geometry/Pastemask Bottom")
		(5 "F.SilkS" user "Ref Des/Silkscreen Top")
		(7 "B.SilkS" user "Ref Des/Silkscreen Bottom")
		(1 "F.Mask" user "Board Geometry/Soldermask Top")
		(3 "B.Mask" user "Board Geometry/Soldermask Bottom")
		(17 "Dwgs.User" user "User.Drawings")
		(19 "Cmts.User" user "User.Comments")
		(21 "Eco1.User" user "User.Eco1")
		(23 "Eco2.User" user "User.Eco2")
		(25 "Edge.Cuts" user "Board Geometry/Outline")
		(27 "Margin" user)
		(31 "F.CrtYd" user "Package Geometry/Place Bound Top")
		(29 "B.CrtYd" user "Package Geometry/Place Bound Bottom")
		(35 "F.Fab" user "Ref Des/Assembly Top")
		(33 "B.Fab" user "Ref Des/Assembly Bottom")
	)
	(footprint ""
		(layer "B.Cu")
		(at 78.345792 -438.897014 180)
		(property "Reference" "X63"
			(at 0.1778 -1.92913 180)
			(unlocked yes)
			(layer "B.SilkS")
			(effects
				(font
					(size 0.7874 0.5842)
					(thickness 0.1524)
				)
				(justify left mirror)
			)
		)
		(property "Value" ""
			(at 0 0 0)
			(layer "B.Fab")
			(effects
				(font
					(size 1.27 1.27)
				)
				(justify mirror)
			)
		)
		(property "Device Type" "TP_TDR_4P_FTS_MPKT4_H025P0200_IO_TP15_TP_TDR_4P_DIP"
			(at -1.30175 1.27 90)
			(unlocked yes)
			(layer "B.Fab")
			(hide yes)
			(effects
				(font
					(size 0.635 0.4064)
					(thickness 0.1524)
				)
				(justify mirror)
			)
		)
		(property "User Part Number" "TP15"
			(at -1.30175 1.27 90)
			(unlocked yes)
			(layer "Cmts.User")
			(hide yes)
			(effects
				(font
					(size 0.635 0.4064)
					(thickness 0.1524)
				)
				(justify mirror)
			)
		)
		(duplicate_pad_numbers_are_jumpers no)
		(fp_line
			(start 0 3.81)
			(end -2.54 3.81)
			(stroke
				(width 0.1524)
				(type default)
			)
			(layer "B.SilkS")
		)
		(fp_line
			(start 0 3.175)
			(end 0 3.81)
			(stroke
				(width 0.1524)
				(type default)
			)
			(layer "B.SilkS")
		)
		(fp_line
			(start 0 0.635)
			(end 0 1.905)
			(stroke
				(width 0.1524)
				(type default)
			)
			(layer "B.SilkS")
		)
		(fp_line
			(start 0 -1.27)
			(end 0 -0.635)
			(stroke
				(width 0.1524)
				(type default)
			)
			(layer "B.SilkS")
		)
		(fp_line
			(start -2.54 3.81)
			(end -2.54 3.6703)
			(stroke
				(width 0.1524)
				(type default)
			)
			(layer "B.SilkS")
		)
		(fp_line
			(start -2.54 1.4097)
			(end -2.54 1.1303)
			(stroke
				(width 0.1524)
				(type default)
			)
			(layer "B.SilkS")
		)
		(fp_line
			(start -2.54 -1.1303)
			(end -2.54 -1.27)
			(stroke
				(width 0.1524)
				(type default)
			)
			(layer "B.SilkS")
		)
		(fp_line
			(start -2.54 -1.27)
			(end 0 -1.27)
			(stroke
				(width 0.1524)
				(type default)
			)
			(layer "B.SilkS")
		)
		(fp_poly
			(pts
				(xy 0.761746 0) (xy 2.285746 -0.762) (xy 2.285746 0.762)
			)
			(stroke
				(width 0)
				(type default)
			)
			(fill yes)
			(layer "B.SilkS")
		)
		(fp_line
			(start 0 3.81)
			(end -2.54 3.81)
			(stroke
				(width 0.1)
				(type default)
			)
			(layer "B.Fab")
		)
		(fp_line
			(start 0 -1.27)
			(end 0 3.81)
			(stroke
				(width 0.1)
				(type default)
			)
			(layer "B.Fab")
		)
		(fp_line
			(start -2.54 3.81)
			(end -2.54 -1.27)
			(stroke
				(width 0.1)
				(type default)
			)
			(layer "B.Fab")
		)
		(fp_line
			(start -2.54 -1.27)
			(end 0 -1.27)
			(stroke
				(width 0.1)
				(type default)
			)
			(layer "B.Fab")
		)
		(fp_poly
			(pts
				(xy 0.761746 0) (xy 2.285746 -0.762) (xy 2.285746 0.762)
			)
			(stroke
				(width 0)
				(type default)
			)
			(fill yes)
			(layer "B.Fab")
		)
		(pad "1" thru_hole circle
			(at 0 0)
			(size 1.0033 1.0033)
			(drill 0.249936)
			(layers "*.Cu" "*.Mask")
			(remove_unused_layers no)
			(net "TDR_DIFF_85_IN5_DIN")
			(clearance 0.10795)
			(padstack
				(mode front_inner_back)
				(layer "Inner"
					(shape circle)
					(size 0.8001 0.8001)
					(clearance 0.1524)
				)
				(layer "B.Cu"
					(shape circle)
					(size 1.0033 1.0033)
					(thermal_gap 0.10795)
					(clearance 0.10795)
				)
			)
		)
		(pad "2" thru_hole circle
			(at -2.54 0)
			(size 1.9939 1.9939)
			(drill 0.249936)
			(layers "*.Cu" "*.Mask")
			(remove_unused_layers no)
			(net "COUPON_GND1")
			(clearance 0.10795)
			(padstack
				(mode front_inner_back)
				(layer "Inner"
					(shape circle)
					(size 0.8001 0.8001)
					(clearance 0.1524)
				)
				(layer "B.Cu"
					(shape circle)
					(size 1.9939 1.9939)
					(thermal_gap 0.10795)
					(clearance 0.10795)
				)
			)
		)
		(pad "3" thru_hole circle
			(at -2.54 2.54)
			(size 1.9939 1.9939)
			(drill 0.249936)
			(layers "*.Cu" "*.Mask")
			(remove_unused_layers no)
			(net "COUPON_GND1")
			(clearance 0.10795)
			(padstack
				(mode front_inner_back)
				(layer "Inner"
					(shape circle)
					(size 0.8001 0.8001)
					(clearance 0.1524)
				)
				(layer "B.Cu"
					(shape circle)
					(size 1.9939 1.9939)
					(thermal_gap 0.10795)
					(clearance 0.10795)
				)
			)
		)
		(pad "4" thru_hole circle
			(at 0 2.54)
			(size 1.0033 1.0033)
			(drill 0.249936)
			(layers "*.Cu" "*.Mask")
			(remove_unused_layers no)
			(net "TDR_DIFF_85_IN5_DIP")
			(clearance 0.10795)
			(padstack
				(mode front_inner_back)
				(layer "Inner"
					(shape circle)
					(size 0.8001 0.8001)
					(clearance 0.1524)
				)
				(layer "B.Cu"
					(shape circle)
					(size 1.0033 1.0033)
					(thermal_gap 0.10795)
					(clearance 0.10795)
				)
			)
		)
	)
	(footprint ""
		(layer "B.Cu")
		(at 159.984694 -447.48831)
		(property "Reference" "X76"
			(at 0.1778 -1.92913 0)
			(unlocked yes)
			(layer "B.SilkS")
			(effects
				(font
					(size 0.7874 0.5842)
					(thickness 0.1524)
				)
				(justify left mirror)
			)
		)
		(property "Value" ""
			(at 0 0 0)
			(layer "B.Fab")
			(effects
				(font
					(size 1.27 1.27)
				)
				(justify mirror)
			)
		)
		(property "Device Type" "TP_TDR_4P_FTS_MPKT4_H025P0200_IO_TP15_TP_TDR_4P_DIP"
			(at -1.30175 1.27 270)
			(unlocked yes)
			(layer "B.Fab")
			(hide yes)
			(effects
				(font
					(size 0.635 0.4064)
					(thickness 0.1524)
				)
				(justify mirror)
			)
		)
		(property "User Part Number" "TP15"
			(at -1.30175 1.27 270)
			(unlocked yes)
			(layer "Cmts.User")
			(hide yes)
			(effects
				(font
					(size 0.635 0.4064)
					(thickness 0.1524)
				)
				(justify mirror)
			)
		)
		(duplicate_pad_numbers_are_jumpers no)
		(fp_line
			(start -2.54 -1.27)
			(end 0 -1.27)
			(stroke
				(width 0.1524)
				(type default)
			)
			(layer "B.SilkS")
		)
		(fp_line
			(start -2.54 -1.1303)
			(end -2.54 -1.27)
			(stroke
				(width 0.1524)
				(type default)
			)
			(layer "B.SilkS")
		)
		(fp_line
			(start -2.54 1.4097)
			(end -2.54 1.1303)
			(stroke
				(width 0.1524)
				(type default)
			)
			(layer "B.SilkS")
		)
		(fp_line
			(start -2.54 3.81)
			(end -2.54 3.6703)
			(stroke
				(width 0.1524)
				(type default)
			)
			(layer "B.SilkS")
		)
		(fp_line
			(start 0 -1.27)
			(end 0 -0.635)
			(stroke
				(width 0.1524)
				(type default)
			)
			(layer "B.SilkS")
		)
		(fp_line
			(start 0 0.635)
			(end 0 1.905)
			(stroke
				(width 0.1524)
				(type default)
			)
			(layer "B.SilkS")
		)
		(fp_line
			(start 0 3.175)
			(end 0 3.81)
			(stroke
				(width 0.1524)
				(type default)
			)
			(layer "B.SilkS")
		)
		(fp_line
			(start 0 3.81)
			(end -2.54 3.81)
			(stroke
				(width 0.1524)
				(type default)
			)
			(layer "B.SilkS")
		)
		(fp_poly
			(pts
				(xy 0.761746 0) (xy 2.285746 -0.762) (xy 2.285746 0.762)
			)
			(stroke
				(width 0)
				(type default)
			)
			(fill yes)
			(layer "B.SilkS")
		)
		(fp_line
			(start -2.54 -1.27)
			(end 0 -1.27)
			(stroke
				(width 0.1)
				(type default)
			)
			(layer "B.Fab")
		)
		(fp_line
			(start -2.54 3.81)
			(end -2.54 -1.27)
			(stroke
				(width 0.1)
				(type default)
			)
			(layer "B.Fab")
		)
		(fp_line
			(start 0 -1.27)
			(end 0 3.81)
			(stroke
				(width 0.1)
				(type default)
			)
			(layer "B.Fab")
		)
		(fp_line
			(start 0 3.81)
			(end -2.54 3.81)
			(stroke
				(width 0.1)
				(type default)
			)
			(layer "B.Fab")
		)
		(fp_poly
			(pts
				(xy 0.761746 0) (xy 2.285746 -0.762) (xy 2.285746 0.762)
			)
			(stroke
				(width 0)
				(type default)
			)
			(fill yes)
			(layer "B.Fab")
		)
		(pad "1" thru_hole circle
			(at 0 0 180)
			(size 1.0033 1.0033)
			(drill 0.249936)
			(layers "*.Cu" "*.Mask")
			(remove_unused_layers no)
			(net "TDR_DIFF_100_IN5_DIP")
			(clearance 0.10795)
			(padstack
				(mode front_inner_back)
				(layer "Inner"
					(shape circle)
					(size 0.8001 0.8001)
					(clearance 0.1524)
				)
				(layer "B.Cu"
					(shape circle)
					(size 1.0033 1.0033)
					(thermal_gap 0.10795)
					(clearance 0.10795)
				)
			)
		)
		(pad "2" thru_hole circle
			(at -2.54 0 180)
			(size 1.9939 1.9939)
			(drill 0.249936)
			(layers "*.Cu" "*.Mask")
			(remove_unused_layers no)
			(net "COUPON_GND1")
			(clearance 0.10795)
			(padstack
				(mode front_inner_back)
				(layer "Inner"
					(shape circle)
					(size 0.8001 0.8001)
					(clearance 0.1524)
				)
				(layer "B.Cu"
					(shape circle)
					(size 1.9939 1.9939)
					(thermal_gap 0.10795)
					(clearance 0.10795)
				)
			)
		)
		(pad "3" thru_hole circle
			(at -2.54 2.54 180)
			(size 1.9939 1.9939)
			(drill 0.249936)
			(layers "*.Cu" "*.Mask")
			(remove_unused_layers no)
			(net "COUPON_GND1")
			(clearance 0.10795)
			(padstack
				(mode front_inner_back)
				(layer "Inner"
					(shape circle)
					(size 0.8001 0.8001)
					(clearance 0.1524)
				)
				(layer "B.Cu"
					(shape circle)
					(size 1.9939 1.9939)
					(thermal_gap 0.10795)
					(clearance 0.10795)
				)
			)
		)
		(pad "4" thru_hole circle
			(at 0 2.54 180)
			(size 1.0033 1.0033)
			(drill 0.249936)
			(layers "*.Cu" "*.Mask")
			(remove_unused_layers no)
			(net "TDR_DIFF_100_IN5_DIN")
			(clearance 0.10795)
			(padstack
				(mode front_inner_back)
				(layer "Inner"
					(shape circle)
					(size 0.8001 0.8001)
					(clearance 0.1524)
				)
				(layer "B.Cu"
					(shape circle)
					(size 1.0033 1.0033)
					(thermal_gap 0.10795)
					(clearance 0.10795)
				)
			)
		)
	)
	(footprint ""
		(layer "B.Cu")
		(at 148.209254 -206.387192 90)
		(property "Reference" "C2608"
			(at 0 0 90)
			(layer "B.SilkS")
			(hide yes)
			(effects
				(font
					(size 1.27 1.27)
				)
				(justify mirror)
			)
		)
		(property "Value" ""
			(at 0 0 90)
			(layer "B.Fab")
			(effects
				(font
					(size 1.27 1.27)
				)
				(justify mirror)
			)
		)
		(duplicate_pad_numbers_are_jumpers no)
		(fp_line
			(start 0.7874 -0.4064)
			(end -0.7874 -0.4064)
			(stroke
				(width 0.1524)
				(type default)
			)
			(layer "B.SilkS")
		)
		(fp_line
			(start -0.7874 -0.4064)
			(end -0.7874 0.4064)
			(stroke
				(width 0.1524)
				(type default)
			)
			(layer "B.SilkS")
		)
		(fp_line
			(start 0.7874 0.4064)
			(end 0.7874 -0.4064)
			(stroke
				(width 0.1524)
				(type default)
			)
			(layer "B.SilkS")
		)
		(fp_line
			(start -0.7874 0.4064)
			(end 0.7874 0.4064)
			(stroke
				(width 0.1524)
				(type default)
			)
			(layer "B.SilkS")
		)
		(fp_line
			(start 0.67945 -0.305054)
			(end 0.12065 -0.305054)
			(stroke
				(width 0.1)
				(type default)
			)
			(layer "B.Fab")
		)
		(fp_line
			(start 0.12065 -0.305054)
			(end 0.12065 -0.2794)
			(stroke
				(width 0.1)
				(type default)
			)
			(layer "B.Fab")
		)
		(fp_line
			(start -0.12065 -0.3048)
			(end -0.67945 -0.3048)
			(stroke
				(width 0.1)
				(type default)
			)
			(layer "B.Fab")
		)
		(fp_line
			(start -0.67945 -0.3048)
			(end -0.67945 0.3048)
			(stroke
				(width 0.1)
				(type default)
			)
			(layer "B.Fab")
		)
		(fp_line
			(start 0.12065 -0.2794)
			(end -0.12065 -0.2794)
			(stroke
				(width 0.1)
				(type default)
			)
			(layer "B.Fab")
		)
		(fp_line
			(start -0.12065 -0.2794)
			(end -0.12065 -0.3048)
			(stroke
				(width 0.1)
				(type default)
			)
			(layer "B.Fab")
		)
		(fp_line
			(start 0.12065 0.2794)
			(end 0.12065 0.3048)
			(stroke
				(width 0.1)
				(type default)
			)
			(layer "B.Fab")
		)
		(fp_line
			(start -0.120396 0.2794)
			(end 0.12065 0.2794)
			(stroke
				(width 0.1)
				(type default)
			)
			(layer "B.Fab")
		)
		(fp_line
			(start 0.67945 0.3048)
			(end 0.67945 -0.305054)
			(stroke
				(width 0.1)
				(type default)
			)
			(layer "B.Fab")
		)
		(fp_line
			(start 0.12065 0.3048)
			(end 0.67945 0.3048)
			(stroke
				(width 0.1)
				(type default)
			)
			(layer "B.Fab")
		)
		(fp_line
			(start -0.120396 0.3048)
			(end -0.120396 0.2794)
			(stroke
				(width 0.1)
				(type default)
			)
			(layer "B.Fab")
		)
		(fp_line
			(start -0.67945 0.3048)
			(end -0.120396 0.3048)
			(stroke
				(width 0.1)
				(type default)
			)
			(layer "B.Fab")
		)
		(pad "1" smd circle
			(at 0.40005 0 270)
			(size 0 0)
			(layers "B.Cu" "B.Mask" "B.Paste")
			(net "GND")
		)
		(pad "2" smd circle
			(at -0.40005 0 270)
			(size 0 0)
			(layers "B.Cu" "B.Mask" "B.Paste")
			(net "P3V3_AUX")
		)
	)
	(footprint ""
		(layer "B.Cu")
		(at 247.17502 -221.640908 90)
		(property "Reference" "R3484"
			(at 0 0 90)
			(layer "B.SilkS")
			(hide yes)
			(effects
				(font
					(size 1.27 1.27)
				)
				(justify mirror)
			)
		)
		(property "Value" ""
			(at 0 0 90)
			(layer "B.Fab")
			(effects
				(font
					(size 1.27 1.27)
				)
				(justify mirror)
			)
		)
		(duplicate_pad_numbers_are_jumpers no)
		(fp_line
			(start 0.7874 -0.4064)
			(end -0.7874 -0.4064)
			(stroke
				(width 0.1524)
				(type default)
			)
			(layer "B.SilkS")
		)
		(fp_line
			(start -0.7874 -0.4064)
			(end -0.7874 0.4064)
			(stroke
				(width 0.1524)
				(type default)
			)
			(layer "B.SilkS")
		)
		(fp_line
			(start 0.7874 0.4064)
			(end 0.7874 -0.4064)
			(stroke
				(width 0.1524)
				(type default)
			)
			(layer "B.SilkS")
		)
		(fp_line
			(start -0.7874 0.4064)
			(end 0.7874 0.4064)
			(stroke
				(width 0.1524)
				(type default)
			)
			(layer "B.SilkS")
		)
		(fp_line
			(start 0.67945 -0.305054)
			(end 0.12065 -0.305054)
			(stroke
				(width 0.1)
				(type default)
			)
			(layer "B.Fab")
		)
		(fp_line
			(start 0.12065 -0.305054)
			(end 0.12065 -0.2794)
			(stroke
				(width 0.1)
				(type default)
			)
			(layer "B.Fab")
		)
		(fp_line
			(start -0.12065 -0.3048)
			(end -0.67945 -0.3048)
			(stroke
				(width 0.1)
				(type default)
			)
			(layer "B.Fab")
		)
		(fp_line
			(start -0.67945 -0.3048)
			(end -0.67945 0.3048)
			(stroke
				(width 0.1)
				(type default)
			)
			(layer "B.Fab")
		)
		(fp_line
			(start 0.12065 -0.2794)
			(end -0.12065 -0.2794)
			(stroke
				(width 0.1)
				(type default)
			)
			(layer "B.Fab")
		)
		(fp_line
			(start -0.12065 -0.2794)
			(end -0.12065 -0.3048)
			(stroke
				(width 0.1)
				(type default)
			)
			(layer "B.Fab")
		)
		(fp_line
			(start 0.12065 0.2794)
			(end 0.12065 0.3048)
			(stroke
				(width 0.1)
				(type default)
			)
			(layer "B.Fab")
		)
		(fp_line
			(start -0.120396 0.2794)
			(end 0.12065 0.2794)
			(stroke
				(width 0.1)
				(type default)
			)
			(layer "B.Fab")
		)
		(fp_line
			(start 0.67945 0.3048)
			(end 0.67945 -0.305054)
			(stroke
				(width 0.1)
				(type default)
			)
			(layer "B.Fab")
		)
		(fp_line
			(start 0.12065 0.3048)
			(end 0.67945 0.3048)
			(stroke
				(width 0.1)
				(type default)
			)
			(layer "B.Fab")
		)
		(fp_line
			(start -0.120396 0.3048)
			(end -0.120396 0.2794)
			(stroke
				(width 0.1)
				(type default)
			)
			(layer "B.Fab")
		)
		(fp_line
			(start -0.67945 0.3048)
			(end -0.120396 0.3048)
			(stroke
				(width 0.1)
				(type default)
			)
			(layer "B.Fab")
		)
		(pad "1" smd circle
			(at 0.40005 0 270)
			(size 0 0)
			(layers "B.Cu" "B.Mask" "B.Paste")
			(net "SPI_PEX2_CLK_MUX")
		)
		(pad "2" smd circle
			(at -0.40005 0 270)
			(size 0 0)
			(layers "B.Cu" "B.Mask" "B.Paste")
			(net "SPI_PEX2_CLK_MUX_R")
		)
	)
	(footprint ""
		(layer "B.Cu")
		(at 287.574736 -286.399732 90)
		(property "Reference" "C3308"
			(at 0 0 90)
			(layer "B.SilkS")
			(hide yes)
			(effects
				(font
					(size 1.27 1.27)
				)
				(justify mirror)
			)
		)
		(property "Value" ""
			(at 0 0 90)
			(layer "B.Fab")
			(effects
				(font
					(size 1.27 1.27)
				)
				(justify mirror)
			)
		)
		(duplicate_pad_numbers_are_jumpers no)
		(fp_line
			(start 0.299974 -0.150114)
			(end -0.299974 -0.150114)
			(stroke
				(width 0.1)
				(type default)
			)
			(layer "B.Fab")
		)
		(fp_line
			(start -0.299974 -0.150114)
			(end -0.299974 0.150114)
			(stroke
				(width 0.1)
				(type default)
			)
			(layer "B.Fab")
		)
		(fp_line
			(start 0.299974 0.150114)
			(end 0.299974 -0.150114)
			(stroke
				(width 0.1)
				(type default)
			)
			(layer "B.Fab")
		)
		(fp_line
			(start -0.299974 0.150114)
			(end 0.299974 0.150114)
			(stroke
				(width 0.1)
				(type default)
			)
			(layer "B.Fab")
		)
		(pad "1" smd rect
			(at 0.2667 0 270)
			(size 0.3048 0.381)
			(layers "B.Cu" "B.Mask" "B.Paste")
			(net "P1V25_SERDES_VDDPLL_PEX2")
		)
		(pad "2" smd rect
			(at -0.2667 0 270)
			(size 0.3048 0.381)
			(layers "B.Cu" "B.Mask" "B.Paste")
			(net "GND")
		)
	)
)
